(kicad_pcb
	(version 20260206)
	(generator "pcbnew")
	(generator_version "10.0")
	(general
		(thickness 1.6)
		(legacy_teardrops no)
	)
	(paper "A4")
	(title_block
		(title "01162023_DA0F0TEBIF0_F0T_Expander_BD_F_brd_V02_OCP.brd")
		(comment 1 "Grand Teton / footprints 1074-1079 of 9728")
	)
	(layers
		(0 "F.Cu" signal "TOP")
		(4 "In1.Cu" signal "GND")
		(6 "In2.Cu" signal "VCC")
		(8 "In3.Cu" signal "VCC1")
		(10 "In4.Cu" signal "GND1")
		(12 "In5.Cu" signal "IN1")
		(14 "In6.Cu" signal "GND2")
		(16 "In7.Cu" signal "IN2")
		(18 "In8.Cu" signal "GND3")
		(20 "In9.Cu" signal "IN3")
		(22 "In10.Cu" signal "GND4")
		(24 "In11.Cu" signal "IN4")
		(26 "In12.Cu" signal "GND5")
		(28 "In13.Cu" signal "IN5")
		(30 "In14.Cu" signal "GND6")
		(32 "In15.Cu" signal "IN6")
		(34 "In16.Cu" signal "GND7")
		(2 "B.Cu" signal "BOTTOM")
		(9 "F.Adhes" user "F.Adhesive")
		(11 "B.Adhes" user "B.Adhesive")
		(13 "F.Paste" user "Package Geometry/Pastemask Top")
		(15 "B.Paste" user "Package Geometry/Pastemask Bottom")
		(5 "F.SilkS" user "Ref Des/Silkscreen Top")
		(7 "B.SilkS" user "Ref Des/Silkscreen Bottom")
		(1 "F.Mask" user "Board Geometry/Soldermask Top")
		(3 "B.Mask" user "Board Geometry/Soldermask Bottom")
		(17 "Dwgs.User" user "User.Drawings")
		(19 "Cmts.User" user "User.Comments")
		(21 "Eco1.User" user "User.Eco1")
		(23 "Eco2.User" user "User.Eco2")
		(25 "Edge.Cuts" user "Board Geometry/Outline")
		(27 "Margin" user)
		(31 "F.CrtYd" user "Package Geometry/Place Bound Top")
		(29 "B.CrtYd" user "Package Geometry/Place Bound Bottom")
		(35 "F.Fab" user "Ref Des/Assembly Top")
		(33 "B.Fab" user "Ref Des/Assembly Bottom")
	)
	(footprint ""
		(layer "F.Cu")
		(at 336.042 -146.939)
		(property "Reference" "R4789"
			(at 0 0 0)
			(layer "F.SilkS")
			(hide yes)
			(effects
				(font
					(size 1.27 1.27)
				)
			)
		)
		(property "Value" ""
			(at 0 0 0)
			(layer "F.Fab")
			(effects
				(font
					(size 1.27 1.27)
				)
			)
		)
		(duplicate_pad_numbers_are_jumpers no)
		(fp_line
			(start -0.7874 -0.4064)
			(end 0.7874 -0.4064)
			(stroke
				(width 0.1524)
				(type default)
			)
			(layer "F.SilkS")
		)
		(fp_line
			(start -0.7874 0.4064)
			(end -0.7874 -0.4064)
			(stroke
				(width 0.1524)
				(type default)
			)
			(layer "F.SilkS")
		)
		(fp_line
			(start 0.7874 -0.4064)
			(end 0.7874 0.4064)
			(stroke
				(width 0.1524)
				(type default)
			)
			(layer "F.SilkS")
		)
		(fp_line
			(start 0.7874 0.4064)
			(end -0.7874 0.4064)
			(stroke
				(width 0.1524)
				(type default)
			)
			(layer "F.SilkS")
		)
		(fp_line
			(start -0.67945 -0.305054)
			(end -0.12065 -0.305054)
			(stroke
				(width 0.1)
				(type default)
			)
			(layer "F.Fab")
		)
		(fp_line
			(start -0.67945 0.3048)
			(end -0.67945 -0.305054)
			(stroke
				(width 0.1)
				(type default)
			)
			(layer "F.Fab")
		)
		(fp_line
			(start -0.12065 -0.305054)
			(end -0.12065 -0.2794)
			(stroke
				(width 0.1)
				(type default)
			)
			(layer "F.Fab")
		)
		(fp_line
			(start -0.12065 -0.2794)
			(end 0.12065 -0.2794)
			(stroke
				(width 0.1)
				(type default)
			)
			(layer "F.Fab")
		)
		(fp_line
			(start -0.12065 0.2794)
			(end -0.12065 0.3048)
			(stroke
				(width 0.1)
				(type default)
			)
			(layer "F.Fab")
		)
		(fp_line
			(start -0.12065 0.3048)
			(end -0.67945 0.3048)
			(stroke
				(width 0.1)
				(type default)
			)
			(layer "F.Fab")
		)
		(fp_line
			(start 0.120396 0.2794)
			(end -0.12065 0.2794)
			(stroke
				(width 0.1)
				(type default)
			)
			(layer "F.Fab")
		)
		(fp_line
			(start 0.120396 0.3048)
			(end 0.120396 0.2794)
			(stroke
				(width 0.1)
				(type default)
			)
			(layer "F.Fab")
		)
		(fp_line
			(start 0.12065 -0.3048)
			(end 0.67945 -0.3048)
			(stroke
				(width 0.1)
				(type default)
			)
			(layer "F.Fab")
		)
		(fp_line
			(start 0.12065 -0.2794)
			(end 0.12065 -0.3048)
			(stroke
				(width 0.1)
				(type default)
			)
			(layer "F.Fab")
		)
		(fp_line
			(start 0.67945 -0.3048)
			(end 0.67945 0.3048)
			(stroke
				(width 0.1)
				(type default)
			)
			(layer "F.Fab")
		)
		(fp_line
			(start 0.67945 0.3048)
			(end 0.120396 0.3048)
			(stroke
				(width 0.1)
				(type default)
			)
			(layer "F.Fab")
		)
		(pad "1" smd circle
			(at -0.40005 0)
			(size 0 0)
			(layers "F.Cu" "F.Mask" "F.Paste")
			(net "P3V3_AUX")
		)
		(pad "2" smd circle
			(at 0.40005 0)
			(size 0 0)
			(layers "F.Cu" "F.Mask" "F.Paste")
			(net "SSD14_PEX_PWR_EN_R")
		)
	)
	(footprint ""
		(layer "F.Cu")
		(at 159.946594 -450.961252 180)
		(property "Reference" "X71"
			(at -0.1778 -1.92913 180)
			(unlocked yes)
			(layer "F.SilkS")
			(effects
				(font
					(size 0.7874 0.5842)
					(thickness 0.1524)
				)
				(justify left)
			)
		)
		(property "Value" ""
			(at 0 0 180)
			(layer "F.Fab")
			(effects
				(font
					(size 1.27 1.27)
				)
			)
		)
		(property "Device Type" "TP_TDR_4P_FTS_MPKT4_H025P0200_IO_TP15_TP_TDR_4P_DIP"
			(at 1.30175 1.27 270)
			(unlocked yes)
			(layer "F.Fab")
			(hide yes)
			(effects
				(font
					(size 0.635 0.4064)
					(thickness 0.1524)
				)
			)
		)
		(property "User Part Number" "TP15"
			(at 1.30175 1.27 270)
			(unlocked yes)
			(layer "Cmts.User")
			(hide yes)
			(effects
				(font
					(size 0.635 0.4064)
					(thickness 0.1524)
				)
			)
		)
		(duplicate_pad_numbers_are_jumpers no)
		(fp_line
			(start 2.54 3.81)
			(end 2.54 3.6703)
			(stroke
				(width 0.1524)
				(type default)
			)
			(layer "F.SilkS")
		)
		(fp_line
			(start 2.54 1.4097)
			(end 2.54 1.1303)
			(stroke
				(width 0.1524)
				(type default)
			)
			(layer "F.SilkS")
		)
		(fp_line
			(start 2.54 -1.1303)
			(end 2.54 -1.27)
			(stroke
				(width 0.1524)
				(type default)
			)
			(layer "F.SilkS")
		)
		(fp_line
			(start 2.54 -1.27)
			(end 0 -1.27)
			(stroke
				(width 0.1524)
				(type default)
			)
			(layer "F.SilkS")
		)
		(fp_line
			(start 0 3.81)
			(end 2.54 3.81)
			(stroke
				(width 0.1524)
				(type default)
			)
			(layer "F.SilkS")
		)
		(fp_line
			(start 0 3.175)
			(end 0 3.81)
			(stroke
				(width 0.1524)
				(type default)
			)
			(layer "F.SilkS")
		)
		(fp_line
			(start 0 0.635)
			(end 0 1.905)
			(stroke
				(width 0.1524)
				(type default)
			)
			(layer "F.SilkS")
		)
		(fp_line
			(start 0 -1.27)
			(end 0 -0.635)
			(stroke
				(width 0.1524)
				(type default)
			)
			(layer "F.SilkS")
		)
		(fp_poly
			(pts
				(xy -0.761746 0) (xy -2.285746 -0.762) (xy -2.285746 0.762)
			)
			(stroke
				(width 0)
				(type default)
			)
			(fill yes)
			(layer "F.SilkS")
		)
		(fp_line
			(start 2.54 3.81)
			(end 2.54 -1.27)
			(stroke
				(width 0.1)
				(type default)
			)
			(layer "F.Fab")
		)
		(fp_line
			(start 2.54 -1.27)
			(end 0 -1.27)
			(stroke
				(width 0.1)
				(type default)
			)
			(layer "F.Fab")
		)
		(fp_line
			(start 0 3.81)
			(end 2.54 3.81)
			(stroke
				(width 0.1)
				(type default)
			)
			(layer "F.Fab")
		)
		(fp_line
			(start 0 -1.27)
			(end 0 3.81)
			(stroke
				(width 0.1)
				(type default)
			)
			(layer "F.Fab")
		)
		(fp_poly
			(pts
				(xy -0.761746 0) (xy -2.285746 -0.762) (xy -2.285746 0.762)
			)
			(stroke
				(width 0)
				(type default)
			)
			(fill yes)
			(layer "F.Fab")
		)
		(pad "1" thru_hole circle
			(at 0 0 180)
			(size 1.0033 1.0033)
			(drill 0.249936)
			(layers "*.Cu" "*.Mask")
			(remove_unused_layers no)
			(net "TDR_DIFF_100_IN2_DIN")
			(clearance 0.10795)
			(thermal_gap 0.10795)
			(padstack
				(mode front_inner_back)
				(layer "Inner"
					(shape circle)
					(size 0.8001 0.8001)
					(clearance 0.1524)
				)
				(layer "B.Cu"
					(shape circle)
					(size 1.0033 1.0033)
					(clearance 0.10795)
				)
			)
		)
		(pad "2" thru_hole circle
			(at 2.54 0 180)
			(size 1.9939 1.9939)
			(drill 0.249936)
			(layers "*.Cu" "*.Mask")
			(remove_unused_layers no)
			(net "COUPON_GND1")
			(clearance 0.10795)
			(thermal_gap 0.10795)
			(padstack
				(mode front_inner_back)
				(layer "Inner"
					(shape circle)
					(size 0.8001 0.8001)
					(clearance 0.1524)
				)
				(layer "B.Cu"
					(shape circle)
					(size 1.9939 1.9939)
					(clearance 0.10795)
				)
			)
		)
		(pad "3" thru_hole circle
			(at 2.54 2.54 180)
			(size 1.9939 1.9939)
			(drill 0.249936)
			(layers "*.Cu" "*.Mask")
			(remove_unused_layers no)
			(net "COUPON_GND1")
			(clearance 0.10795)
			(thermal_gap 0.10795)
			(padstack
				(mode front_inner_back)
				(layer "Inner"
					(shape circle)
					(size 0.8001 0.8001)
					(clearance 0.1524)
				)
				(layer "B.Cu"
					(shape circle)
					(size 1.9939 1.9939)
					(clearance 0.10795)
				)
			)
		)
		(pad "4" thru_hole circle
			(at 0 2.54 180)
			(size 1.0033 1.0033)
			(drill 0.249936)
			(layers "*.Cu" "*.Mask")
			(remove_unused_layers no)
			(net "TDR_DIFF_100_IN2_DIP")
			(clearance 0.10795)
			(thermal_gap 0.10795)
			(padstack
				(mode front_inner_back)
				(layer "Inner"
					(shape circle)
					(size 0.8001 0.8001)
					(clearance 0.1524)
				)
				(layer "B.Cu"
					(shape circle)
					(size 1.0033 1.0033)
					(clearance 0.10795)
				)
			)
		)
	)
	(footprint ""
		(layer "F.Cu")
		(at 20.434554 -30.03169 180)
		(property "Reference" "C70"
			(at 0 0 180)
			(layer "F.SilkS")
			(hide yes)
			(effects
				(font
					(size 1.27 1.27)
				)
			)
		)
		(property "Value" ""
			(at 0 0 180)
			(layer "F.Fab")
			(effects
				(font
					(size 1.27 1.27)
				)
			)
		)
		(duplicate_pad_numbers_are_jumpers no)
		(fp_line
			(start 0.299974 0.150114)
			(end -0.299974 0.150114)
			(stroke
				(width 0.1)
				(type default)
			)
			(layer "F.Fab")
		)
		(fp_line
			(start 0.299974 -0.150114)
			(end 0.299974 0.150114)
			(stroke
				(width 0.1)
				(type default)
			)
			(layer "F.Fab")
		)
		(fp_line
			(start -0.299974 0.150114)
			(end -0.299974 -0.150114)
			(stroke
				(width 0.1)
				(type default)
			)
			(layer "F.Fab")
		)
		(fp_line
			(start -0.299974 -0.150114)
			(end 0.299974 -0.150114)
			(stroke
				(width 0.1)
				(type default)
			)
			(layer "F.Fab")
		)
		(pad "1" smd rect
			(at -0.2667 0 180)
			(size 0.3048 0.381)
			(layers "F.Cu" "F.Mask" "F.Paste")
			(net "P5E_PEX0_STN2_TX_DN<45>")
		)
		(pad "2" smd rect
			(at 0.2667 0 180)
			(size 0.3048 0.381)
			(layers "F.Cu" "F.Mask" "F.Paste")
			(net "P5E_PEX0_STN2_TX_C_DN<45>")
		)
	)
	(footprint ""
		(layer "F.Cu")
		(at 99.8855 -25.1587 -90)
		(property "Reference" "R5738"
			(at 0 0 270)
			(layer "F.SilkS")
			(hide yes)
			(effects
				(font
					(size 1.27 1.27)
				)
			)
		)
		(property "Value" ""
			(at 0 0 270)
			(layer "F.Fab")
			(effects
				(font
					(size 1.27 1.27)
				)
			)
		)
		(duplicate_pad_numbers_are_jumpers no)
		(fp_line
			(start -0.7874 0.4064)
			(end -0.7874 -0.4064)
			(stroke
				(width 0.1524)
				(type default)
			)
			(layer "F.SilkS")
		)
		(fp_line
			(start 0.7874 0.4064)
			(end -0.7874 0.4064)
			(stroke
				(width 0.1524)
				(type default)
			)
			(layer "F.SilkS")
		)
		(fp_line
			(start -0.7874 -0.4064)
			(end 0.7874 -0.4064)
			(stroke
				(width 0.1524)
				(type default)
			)
			(layer "F.SilkS")
		)
		(fp_line
			(start 0.7874 -0.4064)
			(end 0.7874 0.4064)
			(stroke
				(width 0.1524)
				(type default)
			)
			(layer "F.SilkS")
		)
		(fp_line
			(start -0.67945 0.3048)
			(end -0.67945 -0.305054)
			(stroke
				(width 0.1)
				(type default)
			)
			(layer "F.Fab")
		)
		(fp_line
			(start -0.12065 0.3048)
			(end -0.67945 0.3048)
			(stroke
				(width 0.1)
				(type default)
			)
			(layer "F.Fab")
		)
		(fp_line
			(start 0.120396 0.3048)
			(end 0.120396 0.2794)
			(stroke
				(width 0.1)
				(type default)
			)
			(layer "F.Fab")
		)
		(fp_line
			(start 0.67945 0.3048)
			(end 0.120396 0.3048)
			(stroke
				(width 0.1)
				(type default)
			)
			(layer "F.Fab")
		)
		(fp_line
			(start -0.12065 0.2794)
			(end -0.12065 0.3048)
			(stroke
				(width 0.1)
				(type default)
			)
			(layer "F.Fab")
		)
		(fp_line
			(start 0.120396 0.2794)
			(end -0.12065 0.2794)
			(stroke
				(width 0.1)
				(type default)
			)
			(layer "F.Fab")
		)
		(fp_line
			(start -0.12065 -0.2794)
			(end 0.12065 -0.2794)
			(stroke
				(width 0.1)
				(type default)
			)
			(layer "F.Fab")
		)
		(fp_line
			(start 0.12065 -0.2794)
			(end 0.12065 -0.3048)
			(stroke
				(width 0.1)
				(type default)
			)
			(layer "F.Fab")
		)
		(fp_line
			(start 0.12065 -0.3048)
			(end 0.67945 -0.3048)
			(stroke
				(width 0.1)
				(type default)
			)
			(layer "F.Fab")
		)
		(fp_line
			(start 0.67945 -0.3048)
			(end 0.67945 0.3048)
			(stroke
				(width 0.1)
				(type default)
			)
			(layer "F.Fab")
		)
		(fp_line
			(start -0.67945 -0.305054)
			(end -0.12065 -0.305054)
			(stroke
				(width 0.1)
				(type default)
			)
			(layer "F.Fab")
		)
		(fp_line
			(start -0.12065 -0.305054)
			(end -0.12065 -0.2794)
			(stroke
				(width 0.1)
				(type default)
			)
			(layer "F.Fab")
		)
		(pad "1" smd circle
			(at -0.40005 0 270)
			(size 0 0)
			(layers "F.Cu" "F.Mask" "F.Paste")
			(net "SSD3_LED_ISO_N")
		)
		(pad "2" smd circle
			(at 0.40005 0 270)
			(size 0 0)
			(layers "F.Cu" "F.Mask" "F.Paste")
			(net "SSD3_LED_ISO_R_N")
		)
	)
	(footprint ""
		(layer "F.Cu")
		(at 340.614 -201.168 -90)
		(property "Reference" "R4127"
			(at 0 0 270)
			(layer "F.SilkS")
			(hide yes)
			(effects
				(font
					(size 1.27 1.27)
				)
			)
		)
		(property "Value" ""
			(at 0 0 270)
			(layer "F.Fab")
			(effects
				(font
					(size 1.27 1.27)
				)
			)
		)
		(duplicate_pad_numbers_are_jumpers no)
		(fp_line
			(start -0.7874 0.4064)
			(end -0.7874 -0.4064)
			(stroke
				(width 0.1524)
				(type default)
			)
			(layer "F.SilkS")
		)
		(fp_line
			(start 0.7874 0.4064)
			(end -0.7874 0.4064)
			(stroke
				(width 0.1524)
				(type default)
			)
			(layer "F.SilkS")
		)
		(fp_line
			(start -0.7874 -0.4064)
			(end 0.7874 -0.4064)
			(stroke
				(width 0.1524)
				(type default)
			)
			(layer "F.SilkS")
		)
		(fp_line
			(start 0.7874 -0.4064)
			(end 0.7874 0.4064)
			(stroke
				(width 0.1524)
				(type default)
			)
			(layer "F.SilkS")
		)
		(fp_line
			(start -0.67945 0.3048)
			(end -0.67945 -0.305054)
			(stroke
				(width 0.1)
				(type default)
			)
			(layer "F.Fab")
		)
		(fp_line
			(start -0.12065 0.3048)
			(end -0.67945 0.3048)
			(stroke
				(width 0.1)
				(type default)
			)
			(layer "F.Fab")
		)
		(fp_line
			(start 0.120396 0.3048)
			(end 0.120396 0.2794)
			(stroke
				(width 0.1)
				(type default)
			)
			(layer "F.Fab")
		)
		(fp_line
			(start 0.67945 0.3048)
			(end 0.120396 0.3048)
			(stroke
				(width 0.1)
				(type default)
			)
			(layer "F.Fab")
		)
		(fp_line
			(start -0.12065 0.2794)
			(end -0.12065 0.3048)
			(stroke
				(width 0.1)
				(type default)
			)
			(layer "F.Fab")
		)
		(fp_line
			(start 0.120396 0.2794)
			(end -0.12065 0.2794)
			(stroke
				(width 0.1)
				(type default)
			)
			(layer "F.Fab")
		)
		(fp_line
			(start -0.12065 -0.2794)
			(end 0.12065 -0.2794)
			(stroke
				(width 0.1)
				(type default)
			)
			(layer "F.Fab")
		)
		(fp_line
			(start 0.12065 -0.2794)
			(end 0.12065 -0.3048)
			(stroke
				(width 0.1)
				(type default)
			)
			(layer "F.Fab")
		)
		(fp_line
			(start 0.12065 -0.3048)
			(end 0.67945 -0.3048)
			(stroke
				(width 0.1)
				(type default)
			)
			(layer "F.Fab")
		)
		(fp_line
			(start 0.67945 -0.3048)
			(end 0.67945 0.3048)
			(stroke
				(width 0.1)
				(type default)
			)
			(layer "F.Fab")
		)
		(fp_line
			(start -0.67945 -0.305054)
			(end -0.12065 -0.305054)
			(stroke
				(width 0.1)
				(type default)
			)
			(layer "F.Fab")
		)
		(fp_line
			(start -0.12065 -0.305054)
			(end -0.12065 -0.2794)
			(stroke
				(width 0.1)
				(type default)
			)
			(layer "F.Fab")
		)
		(pad "1" smd circle
			(at -0.40005 0 270)
			(size 0 0)
			(layers "F.Cu" "F.Mask" "F.Paste")
			(net "SSD11_PWR_EN")
		)
		(pad "2" smd circle
			(at 0.40005 0 270)
			(size 0 0)
			(layers "F.Cu" "F.Mask" "F.Paste")
			(net "SSD11_PWR_EN_R")
		)
	)
	(footprint ""
		(layer "F.Cu")
		(at 57.754266 -48.21809)
		(property "Reference" "PD65"
			(at -3.195066 2.24536 0)
			(unlocked yes)
			(layer "F.SilkS")
			(effects
				(font
					(size 0.7874 0.5842)
					(thickness 0.1524)
				)
				(justify left)
			)
		)
		(property "Value" ""
			(at 0 0 0)
			(layer "F.Fab")
			(effects
				(font
					(size 1.27 1.27)
				)
			)
		)
		(duplicate_pad_numbers_are_jumpers no)
		(fp_line
			(start -3.400044 -1.459992)
			(end 4.107942 -1.459992)
			(stroke
				(width 0.1524)
				(type default)
			)
			(layer "F.SilkS")
		)
		(fp_line
			(start -3.400044 1.459992)
			(end -3.400044 -1.459992)
			(stroke
				(width 0.1524)
				(type default)
			)
			(layer "F.SilkS")
		)
		(fp_line
			(start 4.107942 -1.459992)
			(end 4.107942 1.459992)
			(stroke
				(width 0.1524)
				(type default)
			)
			(layer "F.SilkS")
		)
		(fp_line
			(start 4.107942 1.459992)
			(end -3.400044 1.459992)
			(stroke
				(width 0.1524)
				(type default)
			)
			(layer "F.SilkS")
		)
		(fp_poly
			(pts
				(xy 4.107942 -1.459992) (xy 4.107942 1.459992) (xy 3.308096 1.459992) (xy 3.308096 -1.459992)
			)
			(stroke
				(width 0)
				(type default)
			)
			(fill yes)
			(layer "F.SilkS")
		)
		(fp_line
			(start -2.29997 -1.459992)
			(end 2.29997 -1.459992)
			(stroke
				(width 0.1)
				(type default)
			)
			(layer "F.Fab")
		)
		(fp_line
			(start -2.29997 1.459992)
			(end -2.29997 -1.459992)
			(stroke
				(width 0.1)
				(type default)
			)
			(layer "F.Fab")
		)
		(fp_line
			(start 2.29997 -1.459992)
			(end 2.29997 1.459992)
			(stroke
				(width 0.1)
				(type default)
			)
			(layer "F.Fab")
		)
		(fp_line
			(start 2.29997 1.459992)
			(end -2.29997 1.459992)
			(stroke
				(width 0.1)
				(type default)
			)
			(layer "F.Fab")
		)
		(fp_text user "+"
			(at -4.7752 -0.12065 0)
			(unlocked yes)
			(layer "F.SilkS")
			(effects
				(font
					(size 1.905 1.4224)
					(thickness 0.1524)
				)
				(justify left)
			)
		)
		(fp_text user "-"
			(at 5.4102 0.29845 180)
			(unlocked yes)
			(layer "F.SilkS")
			(effects
				(font
					(size 1.905 1.4224)
					(thickness 0.1524)
				)
				(justify left)
			)
		)
		(fp_text user "+"
			(at -4.7752 -0.12065 0)
			(unlocked yes)
			(layer "F.Fab")
			(effects
				(font
					(size 1.905 1.4224)
					(thickness 0.1524)
				)
				(justify left)
			)
		)
		(fp_text user "-"
			(at 5.4102 0.29845 180)
			(unlocked yes)
			(layer "F.Fab")
			(effects
				(font
					(size 1.905 1.4224)
					(thickness 0.1524)
				)
				(justify left)
			)
		)
		(pad "A" smd rect
			(at -1.999996 0 90)
			(size 1.7018 2.5146)
			(layers "F.Cu" "F.Mask" "F.Paste")
			(net "GND")
		)
		(pad "C" smd rect
			(at 1.999996 0 90)
			(size 1.7018 2.5146)
			(layers "F.Cu" "F.Mask" "F.Paste")
			(net "P3V3_SSD2")
		)
	)
)
